(kicad_pcb
	(version 20260206)
	(generator "pcbnew")
	(generator_version "10.0")
	(general
		(thickness 1.6)
		(legacy_teardrops no)
	)
	(paper "A4")
	(title_block
		(title "01162023_DA0F0TEBIF0_F0T_Expander_BD_F_brd_V02_OCP.brd")
		(comment 1 "Grand Teton / footprints 6672-6678 of 9728")
	)
	(layers
		(0 "F.Cu" signal "TOP")
		(4 "In1.Cu" signal "GND")
		(6 "In2.Cu" signal "VCC")
		(8 "In3.Cu" signal "VCC1")
		(10 "In4.Cu" signal "GND1")
		(12 "In5.Cu" signal "IN1")
		(14 "In6.Cu" signal "GND2")
		(16 "In7.Cu" signal "IN2")
		(18 "In8.Cu" signal "GND3")
		(20 "In9.Cu" signal "IN3")
		(22 "In10.Cu" signal "GND4")
		(24 "In11.Cu" signal "IN4")
		(26 "In12.Cu" signal "GND5")
		(28 "In13.Cu" signal "IN5")
		(30 "In14.Cu" signal "GND6")
		(32 "In15.Cu" signal "IN6")
		(34 "In16.Cu" signal "GND7")
		(2 "B.Cu" signal "BOTTOM")
		(9 "F.Adhes" user "F.Adhesive")
		(11 "B.Adhes" user "B.Adhesive")
		(13 "F.Paste" user "Package Geometry/Pastemask Top")
		(15 "B.Paste" user "Package Geometry/Pastemask Bottom")
		(5 "F.SilkS" user "Ref Des/Silkscreen Top")
		(7 "B.SilkS" user "Ref Des/Silkscreen Bottom")
		(1 "F.Mask" user "Board Geometry/Soldermask Top")
		(3 "B.Mask" user "Board Geometry/Soldermask Bottom")
		(17 "Dwgs.User" user "User.Drawings")
		(19 "Cmts.User" user "User.Comments")
		(21 "Eco1.User" user "User.Eco1")
		(23 "Eco2.User" user "User.Eco2")
		(25 "Edge.Cuts" user "Board Geometry/Outline")
		(27 "Margin" user)
		(31 "F.CrtYd" user "Package Geometry/Place Bound Top")
		(29 "B.CrtYd" user "Package Geometry/Place Bound Bottom")
		(35 "F.Fab" user "Ref Des/Assembly Top")
		(33 "B.Fab" user "Ref Des/Assembly Bottom")
	)
	(footprint ""
		(layer "F.Cu")
		(at 306.085494 -25.1587 -90)
		(property "Reference" "R5756"
			(at 0 0 270)
			(layer "F.SilkS")
			(hide yes)
			(effects
				(font
					(size 1.27 1.27)
				)
			)
		)
		(property "Value" ""
			(at 0 0 270)
			(layer "F.Fab")
			(effects
				(font
					(size 1.27 1.27)
				)
			)
		)
		(duplicate_pad_numbers_are_jumpers no)
		(fp_line
			(start -0.7874 0.4064)
			(end -0.7874 -0.4064)
			(stroke
				(width 0.1524)
				(type default)
			)
			(layer "F.SilkS")
		)
		(fp_line
			(start 0.7874 0.4064)
			(end -0.7874 0.4064)
			(stroke
				(width 0.1524)
				(type default)
			)
			(layer "F.SilkS")
		)
		(fp_line
			(start -0.7874 -0.4064)
			(end 0.7874 -0.4064)
			(stroke
				(width 0.1524)
				(type default)
			)
			(layer "F.SilkS")
		)
		(fp_line
			(start 0.7874 -0.4064)
			(end 0.7874 0.4064)
			(stroke
				(width 0.1524)
				(type default)
			)
			(layer "F.SilkS")
		)
		(fp_line
			(start -0.67945 0.3048)
			(end -0.67945 -0.305054)
			(stroke
				(width 0.1)
				(type default)
			)
			(layer "F.Fab")
		)
		(fp_line
			(start -0.12065 0.3048)
			(end -0.67945 0.3048)
			(stroke
				(width 0.1)
				(type default)
			)
			(layer "F.Fab")
		)
		(fp_line
			(start 0.120396 0.3048)
			(end 0.120396 0.2794)
			(stroke
				(width 0.1)
				(type default)
			)
			(layer "F.Fab")
		)
		(fp_line
			(start 0.67945 0.3048)
			(end 0.120396 0.3048)
			(stroke
				(width 0.1)
				(type default)
			)
			(layer "F.Fab")
		)
		(fp_line
			(start -0.12065 0.2794)
			(end -0.12065 0.3048)
			(stroke
				(width 0.1)
				(type default)
			)
			(layer "F.Fab")
		)
		(fp_line
			(start 0.120396 0.2794)
			(end -0.12065 0.2794)
			(stroke
				(width 0.1)
				(type default)
			)
			(layer "F.Fab")
		)
		(fp_line
			(start -0.12065 -0.2794)
			(end 0.12065 -0.2794)
			(stroke
				(width 0.1)
				(type default)
			)
			(layer "F.Fab")
		)
		(fp_line
			(start 0.12065 -0.2794)
			(end 0.12065 -0.3048)
			(stroke
				(width 0.1)
				(type default)
			)
			(layer "F.Fab")
		)
		(fp_line
			(start 0.12065 -0.3048)
			(end 0.67945 -0.3048)
			(stroke
				(width 0.1)
				(type default)
			)
			(layer "F.Fab")
		)
		(fp_line
			(start 0.67945 -0.3048)
			(end 0.67945 0.3048)
			(stroke
				(width 0.1)
				(type default)
			)
			(layer "F.Fab")
		)
		(fp_line
			(start -0.67945 -0.305054)
			(end -0.12065 -0.305054)
			(stroke
				(width 0.1)
				(type default)
			)
			(layer "F.Fab")
		)
		(fp_line
			(start -0.12065 -0.305054)
			(end -0.12065 -0.2794)
			(stroke
				(width 0.1)
				(type default)
			)
			(layer "F.Fab")
		)
		(pad "1" smd circle
			(at -0.40005 0 270)
			(size 0 0)
			(layers "F.Cu" "F.Mask" "F.Paste")
			(net "SSD10_LED_ISO_N")
		)
		(pad "2" smd circle
			(at 0.40005 0 270)
			(size 0 0)
			(layers "F.Cu" "F.Mask" "F.Paste")
			(net "SSD10_LED_ISO_R_N")
		)
	)
	(footprint ""
		(layer "F.Cu")
		(at 58.995056 -98.734372)
		(property "Reference" "R52"
			(at 0 0 0)
			(layer "F.SilkS")
			(hide yes)
			(effects
				(font
					(size 1.27 1.27)
				)
			)
		)
		(property "Value" ""
			(at 0 0 0)
			(layer "F.Fab")
			(effects
				(font
					(size 1.27 1.27)
				)
			)
		)
		(duplicate_pad_numbers_are_jumpers no)
		(fp_line
			(start -0.7874 -0.4064)
			(end 0.7874 -0.4064)
			(stroke
				(width 0.1524)
				(type default)
			)
			(layer "F.SilkS")
		)
		(fp_line
			(start -0.7874 0.4064)
			(end -0.7874 -0.4064)
			(stroke
				(width 0.1524)
				(type default)
			)
			(layer "F.SilkS")
		)
		(fp_line
			(start 0.7874 -0.4064)
			(end 0.7874 0.4064)
			(stroke
				(width 0.1524)
				(type default)
			)
			(layer "F.SilkS")
		)
		(fp_line
			(start 0.7874 0.4064)
			(end -0.7874 0.4064)
			(stroke
				(width 0.1524)
				(type default)
			)
			(layer "F.SilkS")
		)
		(fp_line
			(start -0.67945 -0.305054)
			(end -0.12065 -0.305054)
			(stroke
				(width 0.1)
				(type default)
			)
			(layer "F.Fab")
		)
		(fp_line
			(start -0.67945 0.3048)
			(end -0.67945 -0.305054)
			(stroke
				(width 0.1)
				(type default)
			)
			(layer "F.Fab")
		)
		(fp_line
			(start -0.12065 -0.305054)
			(end -0.12065 -0.2794)
			(stroke
				(width 0.1)
				(type default)
			)
			(layer "F.Fab")
		)
		(fp_line
			(start -0.12065 -0.2794)
			(end 0.12065 -0.2794)
			(stroke
				(width 0.1)
				(type default)
			)
			(layer "F.Fab")
		)
		(fp_line
			(start -0.12065 0.2794)
			(end -0.12065 0.3048)
			(stroke
				(width 0.1)
				(type default)
			)
			(layer "F.Fab")
		)
		(fp_line
			(start -0.12065 0.3048)
			(end -0.67945 0.3048)
			(stroke
				(width 0.1)
				(type default)
			)
			(layer "F.Fab")
		)
		(fp_line
			(start 0.120396 0.2794)
			(end -0.12065 0.2794)
			(stroke
				(width 0.1)
				(type default)
			)
			(layer "F.Fab")
		)
		(fp_line
			(start 0.120396 0.3048)
			(end 0.120396 0.2794)
			(stroke
				(width 0.1)
				(type default)
			)
			(layer "F.Fab")
		)
		(fp_line
			(start 0.12065 -0.3048)
			(end 0.67945 -0.3048)
			(stroke
				(width 0.1)
				(type default)
			)
			(layer "F.Fab")
		)
		(fp_line
			(start 0.12065 -0.2794)
			(end 0.12065 -0.3048)
			(stroke
				(width 0.1)
				(type default)
			)
			(layer "F.Fab")
		)
		(fp_line
			(start 0.67945 -0.3048)
			(end 0.67945 0.3048)
			(stroke
				(width 0.1)
				(type default)
			)
			(layer "F.Fab")
		)
		(fp_line
			(start 0.67945 0.3048)
			(end 0.120396 0.3048)
			(stroke
				(width 0.1)
				(type default)
			)
			(layer "F.Fab")
		)
		(pad "1" smd circle
			(at -0.40005 0)
			(size 0 0)
			(layers "F.Cu" "F.Mask" "F.Paste")
			(net "NIC1_RBT_ARB_OUT")
		)
		(pad "2" smd circle
			(at 0.40005 0)
			(size 0 0)
			(layers "F.Cu" "F.Mask" "F.Paste")
			(net "NIC1_RBT_ARB_IN")
		)
	)
	(footprint ""
		(layer "F.Cu")
		(at 428.319438 -143.504666 180)
		(property "Reference" "C648"
			(at 0 0 180)
			(layer "F.SilkS")
			(hide yes)
			(effects
				(font
					(size 1.27 1.27)
				)
			)
		)
		(property "Value" ""
			(at 0 0 180)
			(layer "F.Fab")
			(effects
				(font
					(size 1.27 1.27)
				)
			)
		)
		(duplicate_pad_numbers_are_jumpers no)
		(fp_line
			(start 0.299974 0.150114)
			(end -0.299974 0.150114)
			(stroke
				(width 0.1)
				(type default)
			)
			(layer "F.Fab")
		)
		(fp_line
			(start 0.299974 -0.150114)
			(end 0.299974 0.150114)
			(stroke
				(width 0.1)
				(type default)
			)
			(layer "F.Fab")
		)
		(fp_line
			(start -0.299974 0.150114)
			(end -0.299974 -0.150114)
			(stroke
				(width 0.1)
				(type default)
			)
			(layer "F.Fab")
		)
		(fp_line
			(start -0.299974 -0.150114)
			(end 0.299974 -0.150114)
			(stroke
				(width 0.1)
				(type default)
			)
			(layer "F.Fab")
		)
		(pad "1" smd rect
			(at -0.2667 0 180)
			(size 0.3048 0.381)
			(layers "F.Cu" "F.Mask" "F.Paste")
			(net "P5E_PEX3_STN0_TX_DP<8>")
		)
		(pad "2" smd rect
			(at 0.2667 0 180)
			(size 0.3048 0.381)
			(layers "F.Cu" "F.Mask" "F.Paste")
			(net "P5E_PEX3_STN0_TX_C_DP<8>")
		)
	)
	(footprint ""
		(layer "F.Cu")
		(at 248.375678 -152.71115 -90)
		(property "Reference" "R732"
			(at 0 0 270)
			(layer "F.SilkS")
			(hide yes)
			(effects
				(font
					(size 1.27 1.27)
				)
			)
		)
		(property "Value" ""
			(at 0 0 270)
			(layer "F.Fab")
			(effects
				(font
					(size 1.27 1.27)
				)
			)
		)
		(duplicate_pad_numbers_are_jumpers no)
		(fp_line
			(start -0.7874 0.4064)
			(end -0.7874 -0.4064)
			(stroke
				(width 0.1524)
				(type default)
			)
			(layer "F.SilkS")
		)
		(fp_line
			(start 0.7874 0.4064)
			(end -0.7874 0.4064)
			(stroke
				(width 0.1524)
				(type default)
			)
			(layer "F.SilkS")
		)
		(fp_line
			(start -0.7874 -0.4064)
			(end 0.7874 -0.4064)
			(stroke
				(width 0.1524)
				(type default)
			)
			(layer "F.SilkS")
		)
		(fp_line
			(start 0.7874 -0.4064)
			(end 0.7874 0.4064)
			(stroke
				(width 0.1524)
				(type default)
			)
			(layer "F.SilkS")
		)
		(fp_line
			(start -0.67945 0.3048)
			(end -0.67945 -0.305054)
			(stroke
				(width 0.1)
				(type default)
			)
			(layer "F.Fab")
		)
		(fp_line
			(start -0.12065 0.3048)
			(end -0.67945 0.3048)
			(stroke
				(width 0.1)
				(type default)
			)
			(layer "F.Fab")
		)
		(fp_line
			(start 0.120396 0.3048)
			(end 0.120396 0.2794)
			(stroke
				(width 0.1)
				(type default)
			)
			(layer "F.Fab")
		)
		(fp_line
			(start 0.67945 0.3048)
			(end 0.120396 0.3048)
			(stroke
				(width 0.1)
				(type default)
			)
			(layer "F.Fab")
		)
		(fp_line
			(start -0.12065 0.2794)
			(end -0.12065 0.3048)
			(stroke
				(width 0.1)
				(type default)
			)
			(layer "F.Fab")
		)
		(fp_line
			(start 0.120396 0.2794)
			(end -0.12065 0.2794)
			(stroke
				(width 0.1)
				(type default)
			)
			(layer "F.Fab")
		)
		(fp_line
			(start -0.12065 -0.2794)
			(end 0.12065 -0.2794)
			(stroke
				(width 0.1)
				(type default)
			)
			(layer "F.Fab")
		)
		(fp_line
			(start 0.12065 -0.2794)
			(end 0.12065 -0.3048)
			(stroke
				(width 0.1)
				(type default)
			)
			(layer "F.Fab")
		)
		(fp_line
			(start 0.12065 -0.3048)
			(end 0.67945 -0.3048)
			(stroke
				(width 0.1)
				(type default)
			)
			(layer "F.Fab")
		)
		(fp_line
			(start 0.67945 -0.3048)
			(end 0.67945 0.3048)
			(stroke
				(width 0.1)
				(type default)
			)
			(layer "F.Fab")
		)
		(fp_line
			(start -0.67945 -0.305054)
			(end -0.12065 -0.305054)
			(stroke
				(width 0.1)
				(type default)
			)
			(layer "F.Fab")
		)
		(fp_line
			(start -0.12065 -0.305054)
			(end -0.12065 -0.2794)
			(stroke
				(width 0.1)
				(type default)
			)
			(layer "F.Fab")
		)
		(pad "1" smd circle
			(at -0.40005 0 270)
			(size 0 0)
			(layers "F.Cu" "F.Mask" "F.Paste")
			(net "SMB_BIC_I2C6_MUX_NIC_ADC_R_SDA")
		)
		(pad "2" smd circle
			(at 0.40005 0 270)
			(size 0 0)
			(layers "F.Cu" "F.Mask" "F.Paste")
			(net "SMB_NIC4_ADC_SDA")
		)
	)
	(footprint ""
		(layer "F.Cu")
		(at 328.295 -237.363 90)
		(property "Reference" "Q19"
			(at 1.7018 -1.95453 90)
			(unlocked yes)
			(layer "F.SilkS")
			(effects
				(font
					(size 0.7874 0.5842)
					(thickness 0.1524)
				)
			)
		)
		(property "Value" ""
			(at 0 0 90)
			(layer "F.Fab")
			(effects
				(font
					(size 1.27 1.27)
				)
			)
		)
		(duplicate_pad_numbers_are_jumpers no)
		(fp_line
			(start 1.376172 -1.199896)
			(end 1.376172 1.199896)
			(stroke
				(width 0.1524)
				(type default)
			)
			(layer "F.SilkS")
		)
		(fp_line
			(start 0.508 -1.199896)
			(end 1.376172 -1.199896)
			(stroke
				(width 0.1524)
				(type default)
			)
			(layer "F.SilkS")
		)
		(fp_line
			(start -0.508 -1.199896)
			(end 0 -0.762)
			(stroke
				(width 0.1524)
				(type default)
			)
			(layer "F.SilkS")
		)
		(fp_line
			(start -1.376172 -1.199896)
			(end -0.508 -1.199896)
			(stroke
				(width 0.1524)
				(type default)
			)
			(layer "F.SilkS")
		)
		(fp_line
			(start 0 -0.762)
			(end 0.508 -1.199896)
			(stroke
				(width 0.1524)
				(type default)
			)
			(layer "F.SilkS")
		)
		(fp_line
			(start 1.376172 1.199896)
			(end -1.376172 1.199896)
			(stroke
				(width 0.1524)
				(type default)
			)
			(layer "F.SilkS")
		)
		(fp_line
			(start -1.376172 1.199896)
			(end -1.376172 -1.199896)
			(stroke
				(width 0.1524)
				(type default)
			)
			(layer "F.SilkS")
		)
		(fp_poly
			(pts
				(xy -1.4605 -0.7493) (xy -2.2225 -1.1303) (xy -2.2225 -0.3683)
			)
			(stroke
				(width 0)
				(type default)
			)
			(fill yes)
			(layer "F.SilkS")
		)
		(fp_line
			(start 0.674878 -1.100074)
			(end 0.674878 1.100074)
			(stroke
				(width 0.1)
				(type default)
			)
			(layer "F.Fab")
		)
		(fp_line
			(start -0.674878 -1.100074)
			(end 0.674878 -1.100074)
			(stroke
				(width 0.1)
				(type default)
			)
			(layer "F.Fab")
		)
		(fp_line
			(start 0.674878 1.100074)
			(end -0.674878 1.100074)
			(stroke
				(width 0.1)
				(type default)
			)
			(layer "F.Fab")
		)
		(fp_line
			(start -0.674878 1.100074)
			(end -0.674878 -1.100074)
			(stroke
				(width 0.1)
				(type default)
			)
			(layer "F.Fab")
		)
		(fp_poly
			(pts
				(xy -1.4605 -0.7493) (xy -2.2225 -1.1303) (xy -2.2225 -0.3683)
			)
			(stroke
				(width 0)
				(type default)
			)
			(fill yes)
			(layer "F.Fab")
		)
		(pad "1" smd rect
			(at -0.899922 -0.750062)
			(size 0.6096 0.6096)
			(layers "F.Cu" "F.Mask" "F.Paste")
			(net "GND")
		)
		(pad "2" smd rect
			(at -0.899922 0)
			(size 0.4064 0.6096)
			(layers "F.Cu" "F.Mask" "F.Paste")
			(net "PRSNT_GPU_N")
		)
		(pad "3" smd rect
			(at -0.899922 0.750062)
			(size 0.6096 0.6096)
			(layers "F.Cu" "F.Mask" "F.Paste")
			(net "PRSNT_GPU_ISO_N")
		)
		(pad "4" smd rect
			(at 0.899922 0.750062)
			(size 0.6096 0.6096)
			(layers "F.Cu" "F.Mask" "F.Paste")
			(net "GND")
		)
		(pad "5" smd rect
			(at 0.899922 0)
			(size 0.4064 0.6096)
			(layers "F.Cu" "F.Mask" "F.Paste")
			(net "PRSNT_GPU_ISO")
		)
		(pad "6" smd rect
			(at 0.899922 -0.750062)
			(size 0.6096 0.6096)
			(layers "F.Cu" "F.Mask" "F.Paste")
			(net "PRSNT_GPU_ISO")
		)
	)
	(footprint ""
		(layer "F.Cu")
		(at 131.404868 -343.952322 90)
		(property "Reference" "C2258"
			(at 0 0 90)
			(layer "F.SilkS")
			(hide yes)
			(effects
				(font
					(size 1.27 1.27)
				)
			)
		)
		(property "Value" ""
			(at 0 0 90)
			(layer "F.Fab")
			(effects
				(font
					(size 1.27 1.27)
				)
			)
		)
		(duplicate_pad_numbers_are_jumpers no)
		(fp_line
			(start 0.299974 -0.150114)
			(end 0.299974 0.150114)
			(stroke
				(width 0.1)
				(type default)
			)
			(layer "F.Fab")
		)
		(fp_line
			(start -0.299974 -0.150114)
			(end 0.299974 -0.150114)
			(stroke
				(width 0.1)
				(type default)
			)
			(layer "F.Fab")
		)
		(fp_line
			(start 0.299974 0.150114)
			(end -0.299974 0.150114)
			(stroke
				(width 0.1)
				(type default)
			)
			(layer "F.Fab")
		)
		(fp_line
			(start -0.299974 0.150114)
			(end -0.299974 -0.150114)
			(stroke
				(width 0.1)
				(type default)
			)
			(layer "F.Fab")
		)
		(pad "1" smd rect
			(at -0.2667 0 90)
			(size 0.3048 0.381)
			(layers "F.Cu" "F.Mask" "F.Paste")
			(net "P5E_PEX1_STN5_TX_DN<88>")
		)
		(pad "2" smd rect
			(at 0.2667 0 90)
			(size 0.3048 0.381)
			(layers "F.Cu" "F.Mask" "F.Paste")
			(net "P5E_PEX1_STN5_TX_C_DN<88>")
		)
	)
	(footprint ""
		(layer "F.Cu")
		(at 234.271058 -82.118708)
		(property "Reference" "R6726"
			(at 0 0 0)
			(layer "F.SilkS")
			(hide yes)
			(effects
				(font
					(size 1.27 1.27)
				)
			)
		)
		(property "Value" ""
			(at 0 0 0)
			(layer "F.Fab")
			(effects
				(font
					(size 1.27 1.27)
				)
			)
		)
		(duplicate_pad_numbers_are_jumpers no)
		(fp_line
			(start -0.7874 -0.4064)
			(end 0.7874 -0.4064)
			(stroke
				(width 0.1524)
				(type default)
			)
			(layer "F.SilkS")
		)
		(fp_line
			(start -0.7874 0.4064)
			(end -0.7874 -0.4064)
			(stroke
				(width 0.1524)
				(type default)
			)
			(layer "F.SilkS")
		)
		(fp_line
			(start 0.7874 -0.4064)
			(end 0.7874 0.4064)
			(stroke
				(width 0.1524)
				(type default)
			)
			(layer "F.SilkS")
		)
		(fp_line
			(start 0.7874 0.4064)
			(end 0.004572 0.4064)
			(stroke
				(width 0.1524)
				(type default)
			)
			(layer "F.SilkS")
		)
		(fp_line
			(start -0.67945 -0.305054)
			(end -0.12065 -0.305054)
			(stroke
				(width 0.1)
				(type default)
			)
			(layer "F.Fab")
		)
		(fp_line
			(start -0.67945 0.3048)
			(end -0.67945 -0.305054)
			(stroke
				(width 0.1)
				(type default)
			)
			(layer "F.Fab")
		)
		(fp_line
			(start -0.12065 -0.305054)
			(end -0.12065 -0.2794)
			(stroke
				(width 0.1)
				(type default)
			)
			(layer "F.Fab")
		)
		(fp_line
			(start -0.12065 -0.2794)
			(end 0.12065 -0.2794)
			(stroke
				(width 0.1)
				(type default)
			)
			(layer "F.Fab")
		)
		(fp_line
			(start -0.12065 0.2794)
			(end -0.12065 0.3048)
			(stroke
				(width 0.1)
				(type default)
			)
			(layer "F.Fab")
		)
		(fp_line
			(start -0.12065 0.3048)
			(end -0.67945 0.3048)
			(stroke
				(width 0.1)
				(type default)
			)
			(layer "F.Fab")
		)
		(fp_line
			(start 0.120396 0.2794)
			(end -0.12065 0.2794)
			(stroke
				(width 0.1)
				(type default)
			)
			(layer "F.Fab")
		)
		(fp_line
			(start 0.120396 0.3048)
			(end 0.120396 0.2794)
			(stroke
				(width 0.1)
				(type default)
			)
			(layer "F.Fab")
		)
		(fp_line
			(start 0.12065 -0.3048)
			(end 0.67945 -0.3048)
			(stroke
				(width 0.1)
				(type default)
			)
			(layer "F.Fab")
		)
		(fp_line
			(start 0.12065 -0.2794)
			(end 0.12065 -0.3048)
			(stroke
				(width 0.1)
				(type default)
			)
			(layer "F.Fab")
		)
		(fp_line
			(start 0.67945 -0.3048)
			(end 0.67945 0.3048)
			(stroke
				(width 0.1)
				(type default)
			)
			(layer "F.Fab")
		)
		(fp_line
			(start 0.67945 0.3048)
			(end 0.120396 0.3048)
			(stroke
				(width 0.1)
				(type default)
			)
			(layer "F.Fab")
		)
		(pad "1" smd rect
			(at -0.40005 0 180)
			(size 0.4572 0.508)
			(layers "F.Cu" "F.Mask" "F.Paste")
			(net "USB2_CP2108_SDB_DP")
		)
		(pad "2" smd rect
			(at 0.40005 0 180)
			(size 0.4572 0.508)
			(layers "F.Cu" "F.Mask" "F.Paste")
			(net "GND")
		)
	)
)
